# S9S_MB_2U (Grand Teton) — schematic netlist excerpt (pin names and nets, part order shuffled) for the footprints in the layout excerpt that follows; sources: Cadence DE-HDL packaged netlist, KiCad conversion of 03242023_DA0F0TMBIJ0_F0T_Motherboard_J_brd_V01_OCP.brd

PU202  MAX15090BEWIT  MAX15090BEWI+T IC  pkg BGA28_0-5_3-525X2-065  page 156
  ISENSE  = P3V3_OCP_SENSE_1
  VCC  = P3V3_OCP_VCC_1
  IN_A3  = P3V3_AUX
  OUT_A4  = P3V3_OCP_SFF_R
  IN_A5  = P3V3_AUX
  GATE  = P3V3_OCP_GATE_PU202_1
  CDLY  = GND
  CB  = P3V3_OCP_CB_1
  GND_B2  = GND
  IN_B3  = P3V3_AUX
  OUT_B4  = P3V3_OCP_SFF_R
  IN_B5  = P3V3_AUX
  OUT_B6  = P3V3_OCP_SFF_R
  \en#\  = GND
  GND_C1  = GND
  GND_C2  = GND
  IN_C3  = P3V3_AUX
  OUT_C4  = P3V3_OCP_SFF_R
  IN_C5  = P3V3_AUX
  OUT_C6  = P3V3_OCP_SFF_R
  \fault#\  = P3V3_OCP_FAULT_1
  REG  = P3V3_OCP_REG_1
  UV  = P3V3_OCP_UV_1
  OV  = P3V3_OCP_OV_1
  OUT_D4  = P3V3_OCP_SFF_R
  IN_D5  = P3V3_AUX
  OUT_D6  = P3V3_OCP_SFF_R
  PG  = P3V3_OCP_PWRGD_1

(kicad_pcb
	(version 20260206)
	(generator "pcbnew")
	(generator_version "10.0")
	(general
		(thickness 1.6)
		(legacy_teardrops no)
	)
	(paper "A4")
	(title_block
		(title "03242023_DA0F0TMBIJ0_F0T_Motherboard_J_brd_V01_OCP.brd")
		(comment 1 "Grand Teton / footprints 4133-4133 of 6105")
	)
	(layers
		(0 "F.Cu" signal "TOP")
		(4 "In1.Cu" signal "GND")
		(6 "In2.Cu" signal "IN1")
		(8 "In3.Cu" signal "GND1")
		(10 "In4.Cu" signal "IN2")
		(12 "In5.Cu" signal "GND2")
		(14 "In6.Cu" signal "IN3")
		(16 "In7.Cu" signal "GND3")
		(18 "In8.Cu" signal "VCC")
		(20 "In9.Cu" signal "VCC1")
		(22 "In10.Cu" signal "GND4")
		(24 "In11.Cu" signal "IN4")
		(26 "In12.Cu" signal "GND5")
		(28 "In13.Cu" signal "IN5")
		(30 "In14.Cu" signal "GND6")
		(32 "In15.Cu" signal "IN6")
		(34 "In16.Cu" signal "GND7")
		(2 "B.Cu" signal "BOTTOM")
		(9 "F.Adhes" user "F.Adhesive")
		(11 "B.Adhes" user "B.Adhesive")
		(13 "F.Paste" user "Package Geometry/Pastemask Top")
		(15 "B.Paste" user "Package Geometry/Pastemask Bottom")
		(5 "F.SilkS" user "Ref Des/Silkscreen Top")
		(7 "B.SilkS" user "Ref Des/Silkscreen Bottom")
		(1 "F.Mask" user "Board Geometry/Soldermask Top")
		(3 "B.Mask" user "Board Geometry/Soldermask Bottom")
		(17 "Dwgs.User" user "User.Drawings")
		(19 "Cmts.User" user "User.Comments")
		(21 "Eco1.User" user "User.Eco1")
		(23 "Eco2.User" user "User.Eco2")
		(25 "Edge.Cuts" user "Board Geometry/Outline")
		(27 "Margin" user)
		(31 "F.CrtYd" user "Package Geometry/Place Bound Top")
		(29 "B.CrtYd" user "Package Geometry/Place Bound Bottom")
		(35 "F.Fab" user "Ref Des/Assembly Top")
		(33 "B.Fab" user "Ref Des/Assembly Bottom")
	)
	(footprint ""
		(layer "F.Cu")
		(at 431.828956 -105.32745 -90)
		(property "Reference" "PU202"
			(at 3.334004 -1.70815 0)
			(unlocked yes)
			(layer "F.SilkS")
			(effects
				(font
					(size 0.7874 0.5842)
					(thickness 0.1524)
				)
				(justify left)
			)
		)
		(property "Value" ""
			(at 0 0 270)
			(layer "F.Fab")
			(effects
				(font
					(size 1.27 1.27)
				)
			)
		)
		(duplicate_pad_numbers_are_jumpers no)
		(fp_line
			(start -1.774952 1.039876)
			(end 1.774952 1.039876)
			(stroke
				(width 0.1524)
				(type default)
			)
			(layer "F.SilkS")
		)
		(fp_line
			(start 1.774952 1.039876)
			(end 1.774952 -1.039876)
			(stroke
				(width 0.1524)
				(type default)
			)
			(layer "F.SilkS")
		)
		(fp_line
			(start -1.774952 -1.039876)
			(end -1.774952 1.039876)
			(stroke
				(width 0.1524)
				(type default)
			)
			(layer "F.SilkS")
		)
		(fp_line
			(start 1.774952 -1.039876)
			(end -1.774952 -1.039876)
			(stroke
				(width 0.1524)
				(type default)
			)
			(layer "F.SilkS")
		)
		(fp_poly
			(pts
				(xy -1.769872 -1.039876) (xy -1.769872 -0.249936) (xy -2.531872 -0.249936) (xy -2.531872 -1.801876)
				(xy -0.999998 -1.801876) (xy -0.999998 -1.039876)
			)
			(stroke
				(width 0)
				(type default)
			)
			(fill yes)
			(layer "F.SilkS")
		)
		(fp_line
			(start -1.769872 1.039876)
			(end 1.769872 1.039876)
			(stroke
				(width 0.1)
				(type default)
			)
			(layer "F.Fab")
		)
		(fp_line
			(start 1.769872 1.039876)
			(end 1.769872 -1.039876)
			(stroke
				(width 0.1)
				(type default)
			)
			(layer "F.Fab")
		)
		(fp_line
			(start -1.769872 -1.039876)
			(end -1.769872 1.039876)
			(stroke
				(width 0.1)
				(type default)
			)
			(layer "F.Fab")
		)
		(fp_line
			(start 1.769872 -1.039876)
			(end -1.769872 -1.039876)
			(stroke
				(width 0.1)
				(type default)
			)
			(layer "F.Fab")
		)
		(fp_poly
			(pts
				(xy -1.769872 -1.039876) (xy -0.999998 -1.039876) (xy -0.999998 -1.801876) (xy -2.531872 -1.801876)
				(xy -2.531872 -0.249936) (xy -1.769872 -0.249936)
			)
			(stroke
				(width 0)
				(type default)
			)
			(fill yes)
			(layer "F.Fab")
		)
		(pad "A1" smd circle
			(at -1.500124 -0.750062 270)
			(size 0.2286 0.2286)
			(layers "F.Cu" "F.Mask" "F.Paste")
			(net "P3V3_OCP_SENSE_1")
		)
		(pad "A2" smd circle
			(at -0.999998 -0.750062 270)
			(size 0.2286 0.2286)
			(layers "F.Cu" "F.Mask" "F.Paste")
			(net "P3V3_OCP_VCC_1")
		)
		(pad "A3" smd circle
			(at -0.499872 -0.750062 270)
			(size 0.2286 0.2286)
			(layers "F.Cu" "F.Mask" "F.Paste")
			(net "P3V3_AUX")
		)
		(pad "A4" smd circle
			(at 0 -0.750062 270)
			(size 0.2286 0.2286)
			(layers "F.Cu" "F.Mask" "F.Paste")
			(net "P3V3_OCP_SFF_R")
		)
		(pad "A5" smd circle
			(at 0.499872 -0.750062 270)
			(size 0.2286 0.2286)
			(layers "F.Cu" "F.Mask" "F.Paste")
			(net "P3V3_AUX")
		)
		(pad "A6" smd circle
			(at 0.999998 -0.750062 270)
			(size 0.2286 0.2286)
			(layers "F.Cu" "F.Mask" "F.Paste")
			(net "P3V3_OCP_GATE_PU202_1")
		)
		(pad "A7" smd circle
			(at 1.500124 -0.750062 270)
			(size 0.2286 0.2286)
			(layers "F.Cu" "F.Mask" "F.Paste")
			(net "GND")
		)
		(pad "B1" smd circle
			(at -1.500124 -0.249936 270)
			(size 0.2286 0.2286)
			(layers "F.Cu" "F.Mask" "F.Paste")
			(net "P3V3_OCP_CB_1")
		)
		(pad "B2" smd circle
			(at -0.999998 -0.249936 270)
			(size 0.2286 0.2286)
			(layers "F.Cu" "F.Mask" "F.Paste")
			(net "GND")
		)
		(pad "B3" smd circle
			(at -0.499872 -0.249936 270)
			(size 0.2286 0.2286)
			(layers "F.Cu" "F.Mask" "F.Paste")
			(net "P3V3_AUX")
		)
		(pad "B4" smd circle
			(at 0 -0.249936 270)
			(size 0.2286 0.2286)
			(layers "F.Cu" "F.Mask" "F.Paste")
			(net "P3V3_OCP_SFF_R")
		)
		(pad "B5" smd circle
			(at 0.499872 -0.249936 270)
			(size 0.2286 0.2286)
			(layers "F.Cu" "F.Mask" "F.Paste")
			(net "P3V3_AUX")
		)
		(pad "B6" smd circle
			(at 0.999998 -0.249936 270)
			(size 0.2286 0.2286)
			(layers "F.Cu" "F.Mask" "F.Paste")
			(net "P3V3_OCP_SFF_R")
		)
		(pad "B7" smd circle
			(at 1.500124 -0.249936 270)
			(size 0.2286 0.2286)
			(layers "F.Cu" "F.Mask" "F.Paste")
			(net "GND")
		)
		(pad "C1" smd circle
			(at -1.500124 0.249936 270)
			(size 0.2286 0.2286)
			(layers "F.Cu" "F.Mask" "F.Paste")
			(net "GND")
		)
		(pad "C2" smd circle
			(at -0.999998 0.249936 270)
			(size 0.2286 0.2286)
			(layers "F.Cu" "F.Mask" "F.Paste")
			(net "GND")
		)
		(pad "C3" smd circle
			(at -0.499872 0.249936 270)
			(size 0.2286 0.2286)
			(layers "F.Cu" "F.Mask" "F.Paste")
			(net "P3V3_AUX")
		)
		(pad "C4" smd circle
			(at 0 0.249936 270)
			(size 0.2286 0.2286)
			(layers "F.Cu" "F.Mask" "F.Paste")
			(net "P3V3_OCP_SFF_R")
		)
		(pad "C5" smd circle
			(at 0.499872 0.249936 270)
			(size 0.2286 0.2286)
			(layers "F.Cu" "F.Mask" "F.Paste")
			(net "P3V3_AUX")
		)
		(pad "C6" smd circle
			(at 0.999998 0.249936 270)
			(size 0.2286 0.2286)
			(layers "F.Cu" "F.Mask" "F.Paste")
			(net "P3V3_OCP_SFF_R")
		)
		(pad "C7" smd circle
			(at 1.500124 0.249936 270)
			(size 0.2286 0.2286)
			(layers "F.Cu" "F.Mask" "F.Paste")
			(net "P3V3_OCP_FAULT_1")
		)
		(pad "D1" smd circle
			(at -1.500124 0.750062 270)
			(size 0.2286 0.2286)
			(layers "F.Cu" "F.Mask" "F.Paste")
			(net "P3V3_OCP_REG_1")
		)
		(pad "D2" smd circle
			(at -0.999998 0.750062 270)
			(size 0.2286 0.2286)
			(layers "F.Cu" "F.Mask" "F.Paste")
			(net "P3V3_OCP_UV_1")
		)
		(pad "D3" smd circle
			(at -0.499872 0.750062 270)
			(size 0.2286 0.2286)
			(layers "F.Cu" "F.Mask" "F.Paste")
			(net "P3V3_OCP_OV_1")
		)
		(pad "D4" smd circle
			(at 0 0.750062 270)
			(size 0.2286 0.2286)
			(layers "F.Cu" "F.Mask" "F.Paste")
			(net "P3V3_OCP_SFF_R")
		)
		(pad "D5" smd circle
			(at 0.499872 0.750062 270)
			(size 0.2286 0.2286)
			(layers "F.Cu" "F.Mask" "F.Paste")
			(net "P3V3_AUX")
		)
		(pad "D6" smd circle
			(at 0.999998 0.750062 270)
			(size 0.2286 0.2286)
			(layers "F.Cu" "F.Mask" "F.Paste")
			(net "P3V3_OCP_SFF_R")
		)
		(pad "D7" smd circle
			(at 1.500124 0.750062 270)
			(size 0.2286 0.2286)
			(layers "F.Cu" "F.Mask" "F.Paste")
			(net "P3V3_OCP_PWRGD_1")
		)
	)
)
